(kicad_pcb
	(version 20260206)
	(generator "pcbnew")
	(generator_version "10.0")
	(general
		(thickness 1.6)
		(legacy_teardrops no)
	)
	(paper "A4")
	(title_block
		(title "Bryce Canyon_R.DPB_16317-1_OCP.brd")
		(comment 1 "Bryce Canyon / footprints 969-975 of 2099")
	)
	(layers
		(0 "F.Cu" signal "TOP")
		(4 "In1.Cu" signal "L2GND")
		(6 "In2.Cu" signal "L3")
		(8 "In3.Cu" signal "L4VCC")
		(10 "In4.Cu" signal "L5VCC")
		(12 "In5.Cu" signal "L6")
		(14 "In6.Cu" signal "L7GND")
		(2 "B.Cu" signal "BOTTOM")
		(9 "F.Adhes" user "F.Adhesive")
		(11 "B.Adhes" user "B.Adhesive")
		(13 "F.Paste" user "Package Geometry/Pastemask Top")
		(15 "B.Paste" user "Package Geometry/Pastemask Bottom")
		(5 "F.SilkS" user "Ref Des/Silkscreen Top")
		(7 "B.SilkS" user "Ref Des/Silkscreen Bottom")
		(1 "F.Mask" user "Board Geometry/Soldermask Top")
		(3 "B.Mask" user "Board Geometry/Soldermask Bottom")
		(17 "Dwgs.User" user "User.Drawings")
		(19 "Cmts.User" user "User.Comments")
		(21 "Eco1.User" user "User.Eco1")
		(23 "Eco2.User" user "User.Eco2")
		(25 "Edge.Cuts" user "Board Geometry/Outline")
		(27 "Margin" user)
		(31 "F.CrtYd" user "Package Geometry/Place Bound Top")
		(29 "B.CrtYd" user "Package Geometry/Place Bound Bottom")
		(35 "F.Fab" user "Ref Des/Assembly Top")
		(33 "B.Fab" user "Ref Des/Assembly Bottom")
	)
	(footprint ""
		(layer "F.Cu")
		(at 338.074 -135.509 90)
		(property "Reference" "R500"
			(at 0 0 90)
			(layer "F.SilkS")
			(hide yes)
			(effects
				(font
					(size 1.27 1.27)
				)
			)
		)
		(property "Value" "200KR2F-L-GP"
			(at 0.064008 -3.993896 90)
			(unlocked yes)
			(layer "F.Fab")
			(hide yes)
			(effects
				(font
					(size 1.016 1.016)
					(thickness 0.1524)
				)
			)
		)
		(property "Device Type" "R402H16"
			(at 0.064008 -5.517896 90)
			(unlocked yes)
			(layer "F.Fab")
			(hide yes)
			(effects
				(font
					(size 1.016 1.016)
					(thickness 0.1524)
				)
			)
		)
		(duplicate_pad_numbers_are_jumpers no)
		(fp_line
			(start 0.508 -0.9398)
			(end -0.508 -0.9398)
			(stroke
				(width 0.1524)
				(type default)
			)
			(layer "F.SilkS")
		)
		(fp_line
			(start -0.508 -0.9398)
			(end -0.508 0.9398)
			(stroke
				(width 0.1524)
				(type default)
			)
			(layer "F.SilkS")
		)
		(fp_rect
			(start -0.508 0.9398)
			(end 0.508 -0.9398)
			(stroke
				(width 0)
				(type default)
			)
			(fill no)
			(layer "F.CrtYd")
		)
		(fp_rect
			(start -0.508 0.9398)
			(end 0.508 -0.9398)
			(stroke
				(width 0)
				(type default)
			)
			(fill no)
			(layer "F.Fab")
		)
		(pad "1" smd custom
			(at 0 -0.4445 90)
			(size 0.1397 0.1397)
			(layers "F.Cu" "F.Mask" "F.Paste")
			(net "SW_HDD_R18")
			(options
				(clearance outline)
				(anchor circle)
			)
			(primitives
				(gr_poly
					(pts
						(arc
							(start -0.1778 -0.2794)
							(mid -0.249642 -0.249642)
							(end -0.2794 -0.1778)
						)
						(arc
							(start -0.2794 0.1778)
							(mid -0.249642 0.249642)
							(end -0.1778 0.2794)
						)
						(arc
							(start 0.1778 0.2794)
							(mid 0.249642 0.249642)
							(end 0.2794 0.1778)
						)
						(arc
							(start 0.2794 -0.1778)
							(mid 0.249642 -0.249642)
							(end 0.1778 -0.2794)
						)
					)
					(width 0)
					(fill yes)
				)
			)
		)
		(pad "2" smd custom
			(at 0 0.4445 90)
			(size 0.1397 0.1397)
			(layers "F.Cu" "F.Mask" "F.Paste")
			(net "SW_HDD_N18")
			(options
				(clearance outline)
				(anchor circle)
			)
			(primitives
				(gr_poly
					(pts
						(arc
							(start -0.1778 -0.2794)
							(mid -0.249642 -0.249642)
							(end -0.2794 -0.1778)
						)
						(arc
							(start -0.2794 0.1778)
							(mid -0.249642 0.249642)
							(end -0.1778 0.2794)
						)
						(arc
							(start 0.1778 0.2794)
							(mid 0.249642 0.249642)
							(end 0.2794 0.1778)
						)
						(arc
							(start 0.2794 -0.1778)
							(mid 0.249642 -0.249642)
							(end 0.1778 -0.2794)
						)
					)
					(width 0)
					(fill yes)
				)
			)
		)
	)
	(footprint ""
		(layer "F.Cu")
		(at 364.998 -274.955 180)
		(property "Reference" "C127"
			(at 0 0 180)
			(layer "F.SilkS")
			(hide yes)
			(effects
				(font
					(size 1.27 1.27)
				)
			)
		)
		(property "Value" "SC4D7U25V5KX-1-GP"
			(at -0.0762 -6.1214 180)
			(unlocked yes)
			(layer "F.Fab")
			(hide yes)
			(effects
				(font
					(size 1.016 1.016)
					(thickness 0.1524)
				)
			)
		)
		(property "Device Type" "C805H58"
			(at -0.0762 -8.1534 180)
			(unlocked yes)
			(layer "F.Fab")
			(hide yes)
			(effects
				(font
					(size 1.016 1.016)
					(thickness 0.1524)
				)
			)
		)
		(duplicate_pad_numbers_are_jumpers no)
		(fp_line
			(start 0.635 0)
			(end -0.635 0)
			(stroke
				(width 0.508)
				(type default)
			)
			(layer "F.SilkS")
		)
		(fp_rect
			(start -0.9652 1.778)
			(end 0.9652 -1.778)
			(stroke
				(width 0)
				(type default)
			)
			(fill no)
			(layer "F.CrtYd")
		)
		(fp_poly
			(pts
				(xy -0.9652 -1.778) (xy 0.9652 -1.778) (xy 0.9652 1.778) (xy -0.9652 1.778)
			)
			(stroke
				(width 0)
				(type default)
			)
			(fill no)
			(layer "F.Fab")
		)
		(pad "1" smd rect
			(at 0 -0.9652 180)
			(size 1.397 1.143)
			(layers "F.Cu" "F.Mask" "F.Paste")
			(net "P12V_HDD7")
		)
		(pad "2" smd rect
			(at 0 0.9652 180)
			(size 1.397 1.143)
			(layers "F.Cu" "F.Mask" "F.Paste")
			(net "GND")
		)
	)
	(footprint ""
		(layer "F.Cu")
		(at 48.029368 -99.798378 90)
		(property "Reference" "Q256"
			(at 0 0 90)
			(layer "F.SilkS")
			(hide yes)
			(effects
				(font
					(size 1.27 1.27)
				)
			)
		)
		(property "Value" "SSM3K324R-GP"
			(at 0.127 -8.9662 90)
			(unlocked yes)
			(layer "F.Fab")
			(hide yes)
			(effects
				(font
					(size 1.016 1.016)
					(thickness 0.1524)
				)
			)
		)
		(property "Device Type" "SOT23DGS2D4H35"
			(at 0.127 -10.4902 90)
			(unlocked yes)
			(layer "F.Fab")
			(hide yes)
			(effects
				(font
					(size 1.016 1.016)
					(thickness 0.1524)
				)
			)
		)
		(duplicate_pad_numbers_are_jumpers no)
		(fp_line
			(start 1.651 -1.778)
			(end -1.651 -1.778)
			(stroke
				(width 0.1524)
				(type default)
			)
			(layer "F.SilkS")
		)
		(fp_line
			(start -1.651 -1.778)
			(end -1.651 1.778)
			(stroke
				(width 0.1524)
				(type default)
			)
			(layer "F.SilkS")
		)
		(fp_line
			(start 1.651 1.778)
			(end 1.651 -1.778)
			(stroke
				(width 0.1524)
				(type default)
			)
			(layer "F.SilkS")
		)
		(fp_line
			(start -1.651 1.778)
			(end 1.651 1.778)
			(stroke
				(width 0.1524)
				(type default)
			)
			(layer "F.SilkS")
		)
		(fp_poly
			(pts
				(xy -1.778 1.8796) (xy -1.778 -1.8796) (xy 1.778 -1.8796) (xy 1.778 1.8796)
			)
			(stroke
				(width 0)
				(type default)
			)
			(fill no)
			(layer "F.CrtYd")
		)
		(fp_poly
			(pts
				(xy -1.778 1.8796) (xy -1.778 -1.8796) (xy 1.778 -1.8796) (xy 1.778 1.8796)
			)
			(stroke
				(width 0)
				(type default)
			)
			(fill no)
			(layer "F.Fab")
		)
		(pad "D" smd custom
			(at 0 -0.9525 90)
			(size 0.1905 0.1905)
			(layers "F.Cu" "F.Mask" "F.Paste")
			(net "DRV_ACT_13_N")
			(options
				(clearance outline)
				(anchor circle)
			)
			(primitives
				(gr_poly
					(pts
						(arc
							(start -0.1778 0.5715)
							(mid -0.321484 0.511984)
							(end -0.381 0.3683)
						)
						(arc
							(start -0.381 -0.3683)
							(mid -0.321484 -0.511984)
							(end -0.1778 -0.5715)
						)
						(arc
							(start 0.1778 -0.5715)
							(mid 0.321484 -0.511984)
							(end 0.381 -0.3683)
						)
						(arc
							(start 0.381 0.3683)
							(mid 0.321484 0.511984)
							(end 0.1778 0.5715)
						)
					)
					(width 0)
					(fill yes)
				)
			)
		)
		(pad "G" smd custom
			(at -0.98425 0.9525 90)
			(size 0.1905 0.1905)
			(layers "F.Cu" "F.Mask" "F.Paste")
			(net "DRIVE_B_13_ACT")
			(options
				(clearance outline)
				(anchor circle)
			)
			(primitives
				(gr_poly
					(pts
						(arc
							(start -0.1778 0.5715)
							(mid -0.321484 0.511984)
							(end -0.381 0.3683)
						)
						(arc
							(start -0.381 -0.3683)
							(mid -0.321484 -0.511984)
							(end -0.1778 -0.5715)
						)
						(arc
							(start 0.1778 -0.5715)
							(mid 0.321484 -0.511984)
							(end 0.381 -0.3683)
						)
						(arc
							(start 0.381 0.3683)
							(mid 0.321484 0.511984)
							(end 0.1778 0.5715)
						)
					)
					(width 0)
					(fill yes)
				)
			)
		)
		(pad "S" smd custom
			(at 0.98425 0.9525 90)
			(size 0.1905 0.1905)
			(layers "F.Cu" "F.Mask" "F.Paste")
			(net "GND")
			(options
				(clearance outline)
				(anchor circle)
			)
			(primitives
				(gr_poly
					(pts
						(arc
							(start -0.1778 0.5715)
							(mid -0.321484 0.511984)
							(end -0.381 0.3683)
						)
						(arc
							(start -0.381 -0.3683)
							(mid -0.321484 -0.511984)
							(end -0.1778 -0.5715)
						)
						(arc
							(start 0.1778 -0.5715)
							(mid 0.321484 -0.511984)
							(end 0.381 -0.3683)
						)
						(arc
							(start 0.381 0.3683)
							(mid 0.321484 0.511984)
							(end 0.1778 0.5715)
						)
					)
					(width 0)
					(fill yes)
				)
			)
		)
	)
	(footprint ""
		(layer "F.Cu")
		(at 349.7326 -261.3152)
		(property "Reference" "R273"
			(at 0 0 0)
			(layer "F.SilkS")
			(hide yes)
			(effects
				(font
					(size 1.27 1.27)
				)
			)
		)
		(property "Value" "220R3F-1-GP"
			(at -0.0254 -2.5146 0)
			(unlocked yes)
			(layer "F.Fab")
			(hide yes)
			(effects
				(font
					(size 1.016 1.016)
					(thickness 0.1524)
				)
			)
		)
		(property "Device Type" "R603H22"
			(at -0.0254 -4.0386 0)
			(unlocked yes)
			(layer "F.Fab")
			(hide yes)
			(effects
				(font
					(size 1.016 1.016)
					(thickness 0.1524)
				)
			)
		)
		(duplicate_pad_numbers_are_jumpers no)
		(fp_line
			(start -0.4826 0)
			(end -0.2032 0)
			(stroke
				(width 0.2032)
				(type default)
			)
			(layer "F.SilkS")
		)
		(fp_line
			(start 0.2032 0)
			(end 0.4826 0)
			(stroke
				(width 0.2032)
				(type default)
			)
			(layer "F.SilkS")
		)
		(fp_rect
			(start -0.5842 1.3335)
			(end 0.5842 -1.3335)
			(stroke
				(width 0)
				(type default)
			)
			(fill no)
			(layer "F.CrtYd")
		)
		(fp_rect
			(start -0.5842 1.3335)
			(end 0.5842 -1.3335)
			(stroke
				(width 0)
				(type default)
			)
			(fill no)
			(layer "F.Fab")
		)
		(pad "1" smd custom
			(at 0 -0.762)
			(size 0.2159 0.2159)
			(layers "F.Cu" "F.Mask" "F.Paste")
			(net "HDD_PRSNT_7")
			(options
				(clearance outline)
				(anchor circle)
			)
			(primitives
				(gr_poly
					(pts
						(arc
							(start -0.3302 -0.4318)
							(mid -0.402042 -0.402042)
							(end -0.4318 -0.3302)
						)
						(arc
							(start -0.4318 0.3302)
							(mid -0.402042 0.402042)
							(end -0.3302 0.4318)
						)
						(arc
							(start 0.3302 0.4318)
							(mid 0.402042 0.402042)
							(end 0.4318 0.3302)
						)
						(arc
							(start 0.4318 -0.3302)
							(mid 0.402042 -0.402042)
							(end 0.3302 -0.4318)
						)
					)
					(width 0)
					(fill yes)
				)
			)
		)
		(pad "2" smd custom
			(at 0 0.762)
			(size 0.2159 0.2159)
			(layers "F.Cu" "F.Mask" "F.Paste")
			(net "DRIVE_B_7_INS")
			(options
				(clearance outline)
				(anchor circle)
			)
			(primitives
				(gr_poly
					(pts
						(arc
							(start -0.3302 -0.4318)
							(mid -0.402042 -0.402042)
							(end -0.4318 -0.3302)
						)
						(arc
							(start -0.4318 0.3302)
							(mid -0.402042 0.402042)
							(end -0.3302 0.4318)
						)
						(arc
							(start 0.3302 0.4318)
							(mid 0.402042 0.402042)
							(end 0.4318 0.3302)
						)
						(arc
							(start 0.4318 -0.3302)
							(mid 0.402042 -0.402042)
							(end 0.3302 -0.4318)
						)
					)
					(width 0)
					(fill yes)
				)
			)
		)
	)
	(footprint ""
		(layer "F.Cu")
		(at 464.185 -135.509 90)
		(property "Reference" "R592"
			(at 0 0 90)
			(layer "F.SilkS")
			(hide yes)
			(effects
				(font
					(size 1.27 1.27)
				)
			)
		)
		(property "Value" "200KR2F-L-GP"
			(at 0.064008 -3.993896 90)
			(unlocked yes)
			(layer "F.Fab")
			(hide yes)
			(effects
				(font
					(size 1.016 1.016)
					(thickness 0.1524)
				)
			)
		)
		(property "Device Type" "R402H16"
			(at 0.064008 -5.517896 90)
			(unlocked yes)
			(layer "F.Fab")
			(hide yes)
			(effects
				(font
					(size 1.016 1.016)
					(thickness 0.1524)
				)
			)
		)
		(duplicate_pad_numbers_are_jumpers no)
		(fp_line
			(start 0.508 -0.9398)
			(end -0.508 -0.9398)
			(stroke
				(width 0.1524)
				(type default)
			)
			(layer "F.SilkS")
		)
		(fp_line
			(start -0.508 -0.9398)
			(end -0.508 0.9398)
			(stroke
				(width 0.1524)
				(type default)
			)
			(layer "F.SilkS")
		)
		(fp_rect
			(start -0.508 0.9398)
			(end 0.508 -0.9398)
			(stroke
				(width 0)
				(type default)
			)
			(fill no)
			(layer "F.CrtYd")
		)
		(fp_rect
			(start -0.508 0.9398)
			(end 0.508 -0.9398)
			(stroke
				(width 0)
				(type default)
			)
			(fill no)
			(layer "F.Fab")
		)
		(pad "1" smd custom
			(at 0 -0.4445 90)
			(size 0.1397 0.1397)
			(layers "F.Cu" "F.Mask" "F.Paste")
			(net "SW_HDD_R22")
			(options
				(clearance outline)
				(anchor circle)
			)
			(primitives
				(gr_poly
					(pts
						(arc
							(start -0.1778 -0.2794)
							(mid -0.249642 -0.249642)
							(end -0.2794 -0.1778)
						)
						(arc
							(start -0.2794 0.1778)
							(mid -0.249642 0.249642)
							(end -0.1778 0.2794)
						)
						(arc
							(start 0.1778 0.2794)
							(mid 0.249642 0.249642)
							(end 0.2794 0.1778)
						)
						(arc
							(start 0.2794 -0.1778)
							(mid 0.249642 -0.249642)
							(end 0.1778 -0.2794)
						)
					)
					(width 0)
					(fill yes)
				)
			)
		)
		(pad "2" smd custom
			(at 0 0.4445 90)
			(size 0.1397 0.1397)
			(layers "F.Cu" "F.Mask" "F.Paste")
			(net "SW_HDD_N22")
			(options
				(clearance outline)
				(anchor circle)
			)
			(primitives
				(gr_poly
					(pts
						(arc
							(start -0.1778 -0.2794)
							(mid -0.249642 -0.249642)
							(end -0.2794 -0.1778)
						)
						(arc
							(start -0.2794 0.1778)
							(mid -0.249642 0.249642)
							(end -0.1778 0.2794)
						)
						(arc
							(start 0.1778 0.2794)
							(mid 0.249642 0.249642)
							(end 0.2794 0.1778)
						)
						(arc
							(start 0.2794 -0.1778)
							(mid 0.249642 -0.249642)
							(end 0.1778 -0.2794)
						)
					)
					(width 0)
					(fill yes)
				)
			)
		)
	)
	(footprint ""
		(layer "F.Cu")
		(at 98.425 -262.128 90)
		(property "Reference" "C63"
			(at 0 0 90)
			(layer "F.SilkS")
			(hide yes)
			(effects
				(font
					(size 1.27 1.27)
				)
			)
		)
		(property "Value" "SCD01U50V2KX-1GP"
			(at 1.1811 -2.7051 90)
			(unlocked yes)
			(layer "F.Fab")
			(hide yes)
			(effects
				(font
					(size 1.016 1.016)
					(thickness 0.1524)
				)
			)
		)
		(property "Device Type" "C402H22"
			(at 1.1811 -4.2291 90)
			(unlocked yes)
			(layer "F.Fab")
			(hide yes)
			(effects
				(font
					(size 1.016 1.016)
					(thickness 0.1524)
				)
			)
		)
		(duplicate_pad_numbers_are_jumpers no)
		(fp_rect
			(start -0.4318 0.9525)
			(end 0.4318 -0.9525)
			(stroke
				(width 0)
				(type default)
			)
			(fill no)
			(layer "F.CrtYd")
		)
		(fp_rect
			(start -0.4318 0.9525)
			(end 0.4318 -0.9525)
			(stroke
				(width 0)
				(type default)
			)
			(fill no)
			(layer "F.Fab")
		)
		(pad "1" smd custom
			(at 0 -0.4445 90)
			(size 0.1524 0.1524)
			(layers "F.Cu" "F.Mask" "F.Paste")
			(net "HDD_PRSNT_2")
			(options
				(clearance outline)
				(anchor circle)
			)
			(primitives
				(gr_poly
					(pts
						(arc
							(start 0.3048 -0.2032)
							(mid 0.275042 -0.275042)
							(end 0.2032 -0.3048)
						)
						(arc
							(start -0.2032 -0.3048)
							(mid -0.275042 -0.275042)
							(end -0.3048 -0.2032)
						)
						(arc
							(start -0.3048 0.2032)
							(mid -0.275042 0.275042)
							(end -0.2032 0.3048)
						)
						(arc
							(start 0.2032 0.3048)
							(mid 0.275042 0.275042)
							(end 0.3048 0.2032)
						)
					)
					(width 0)
					(fill yes)
				)
			)
		)
		(pad "2" smd custom
			(at 0 0.4445 90)
			(size 0.1524 0.1524)
			(layers "F.Cu" "F.Mask" "F.Paste")
			(net "GND")
			(options
				(clearance outline)
				(anchor circle)
			)
			(primitives
				(gr_poly
					(pts
						(arc
							(start 0.3048 -0.2032)
							(mid 0.275042 -0.275042)
							(end 0.2032 -0.3048)
						)
						(arc
							(start -0.2032 -0.3048)
							(mid -0.275042 -0.275042)
							(end -0.3048 -0.2032)
						)
						(arc
							(start -0.3048 0.2032)
							(mid -0.275042 0.275042)
							(end -0.2032 0.3048)
						)
						(arc
							(start 0.2032 0.3048)
							(mid 0.275042 0.275042)
							(end 0.3048 0.2032)
						)
					)
					(width 0)
					(fill yes)
				)
			)
		)
	)
	(footprint ""
		(layer "F.Cu")
		(at 55.753 -160.401 180)
		(property "Reference" "C206"
			(at 0 0 180)
			(layer "F.SilkS")
			(hide yes)
			(effects
				(font
					(size 1.27 1.27)
				)
			)
		)
		(property "Value" "SC1U25V3KX-GP"
			(at 0 -2.8194 180)
			(unlocked yes)
			(layer "F.Fab")
			(hide yes)
			(effects
				(font
					(size 1.016 1.016)
					(thickness 0.1524)
				)
			)
		)
		(property "Device Type" "C603H36"
			(at 0 -4.3434 180)
			(unlocked yes)
			(layer "F.Fab")
			(hide yes)
			(effects
				(font
					(size 1.016 1.016)
					(thickness 0.1524)
				)
			)
		)
		(duplicate_pad_numbers_are_jumpers no)
		(fp_line
			(start 0.508 0)
			(end -0.508 0)
			(stroke
				(width 0.2032)
				(type default)
			)
			(layer "F.SilkS")
		)
		(fp_rect
			(start -0.5842 1.3335)
			(end 0.5842 -1.3335)
			(stroke
				(width 0)
				(type default)
			)
			(fill no)
			(layer "F.CrtYd")
		)
		(fp_rect
			(start -0.5842 1.3335)
			(end 0.5842 -1.3335)
			(stroke
				(width 0)
				(type default)
			)
			(fill no)
			(layer "F.Fab")
		)
		(pad "1" smd custom
			(at 0 -0.762 180)
			(size 0.2159 0.2159)
			(layers "F.Cu" "F.Mask" "F.Paste")
			(net "P12V_HDD13")
			(options
				(clearance outline)
				(anchor circle)
			)
			(primitives
				(gr_poly
					(pts
						(arc
							(start -0.3302 -0.4318)
							(mid -0.402042 -0.402042)
							(end -0.4318 -0.3302)
						)
						(arc
							(start -0.4318 0.3302)
							(mid -0.402042 0.402042)
							(end -0.3302 0.4318)
						)
						(arc
							(start 0.3302 0.4318)
							(mid 0.402042 0.402042)
							(end 0.4318 0.3302)
						)
						(arc
							(start 0.4318 -0.3302)
							(mid 0.402042 -0.402042)
							(end 0.3302 -0.4318)
						)
					)
					(width 0)
					(fill yes)
				)
			)
		)
		(pad "2" smd custom
			(at 0 0.762 180)
			(size 0.2159 0.2159)
			(layers "F.Cu" "F.Mask" "F.Paste")
			(net "GND")
			(options
				(clearance outline)
				(anchor circle)
			)
			(primitives
				(gr_poly
					(pts
						(arc
							(start -0.3302 -0.4318)
							(mid -0.402042 -0.402042)
							(end -0.4318 -0.3302)
						)
						(arc
							(start -0.4318 0.3302)
							(mid -0.402042 0.402042)
							(end -0.3302 0.4318)
						)
						(arc
							(start 0.3302 0.4318)
							(mid 0.402042 0.402042)
							(end 0.4318 0.3302)
						)
						(arc
							(start 0.4318 -0.3302)
							(mid 0.402042 -0.402042)
							(end 0.3302 -0.4318)
						)
					)
					(width 0)
					(fill yes)
				)
			)
		)
	)
)
